# S9S_MB_2U (Grand Teton) — schematic netlist excerpt (pin names and nets, part order shuffled) for the footprints in the layout excerpt that follows; sources: Cadence DE-HDL packaged netlist, KiCad conversion of 03242023_DA0F0TMBIJ0_F0T_Motherboard_J_brd_V01_OCP.brd

R3114  Q_RES  33.2 1% CHIP  pkg 0402LF  page 245 : A = SMB_FAN_3V3AUX_SDA ; B = SMB_FAN_3V3AUX_R_SDA
C314  Q_CAP  47UF 4V 20% X6S  pkg C0805  page 78 : A = PVCCIN_CPU1 ; B = GND
PR142  Q_RES  0 5% CHIP  pkg 0402LF  page 269 : A = PVCCIN_CPU0_VOS6 ; B = PVCCIN_CPU0

(kicad_pcb
	(version 20260206)
	(generator "pcbnew")
	(generator_version "10.0")
	(general
		(thickness 1.6)
		(legacy_teardrops no)
	)
	(paper "A4")
	(title_block
		(title "03242023_DA0F0TMBIJ0_F0T_Motherboard_J_brd_V01_OCP.brd")
		(comment 1 "Grand Teton / footprints 4292-4294 of 6105")
	)
	(layers
		(0 "F.Cu" signal "TOP")
		(4 "In1.Cu" signal "GND")
		(6 "In2.Cu" signal "IN1")
		(8 "In3.Cu" signal "GND1")
		(10 "In4.Cu" signal "IN2")
		(12 "In5.Cu" signal "GND2")
		(14 "In6.Cu" signal "IN3")
		(16 "In7.Cu" signal "GND3")
		(18 "In8.Cu" signal "VCC")
		(20 "In9.Cu" signal "VCC1")
		(22 "In10.Cu" signal "GND4")
		(24 "In11.Cu" signal "IN4")
		(26 "In12.Cu" signal "GND5")
		(28 "In13.Cu" signal "IN5")
		(30 "In14.Cu" signal "GND6")
		(32 "In15.Cu" signal "IN6")
		(34 "In16.Cu" signal "GND7")
		(2 "B.Cu" signal "BOTTOM")
		(9 "F.Adhes" user "F.Adhesive")
		(11 "B.Adhes" user "B.Adhesive")
		(13 "F.Paste" user "Package Geometry/Pastemask Top")
		(15 "B.Paste" user "Package Geometry/Pastemask Bottom")
		(5 "F.SilkS" user "Ref Des/Silkscreen Top")
		(7 "B.SilkS" user "Ref Des/Silkscreen Bottom")
		(1 "F.Mask" user "Board Geometry/Soldermask Top")
		(3 "B.Mask" user "Board Geometry/Soldermask Bottom")
		(17 "Dwgs.User" user "User.Drawings")
		(19 "Cmts.User" user "User.Comments")
		(21 "Eco1.User" user "User.Eco1")
		(23 "Eco2.User" user "User.Eco2")
		(25 "Edge.Cuts" user "Board Geometry/Outline")
		(27 "Margin" user)
		(31 "F.CrtYd" user "Package Geometry/Place Bound Top")
		(29 "B.CrtYd" user "Package Geometry/Place Bound Bottom")
		(35 "F.Fab" user "Ref Des/Assembly Top")
		(33 "B.Fab" user "Ref Des/Assembly Bottom")
	)
	(footprint ""
		(layer "B.Cu")
		(at 333.32928 -339.983572 -90)
		(property "Reference" "PR142"
			(at 0 0 90)
			(layer "B.SilkS")
			(hide yes)
			(effects
				(font
					(size 1.27 1.27)
				)
				(justify mirror)
			)
		)
		(property "Value" ""
			(at 0 0 90)
			(layer "B.Fab")
			(effects
				(font
					(size 1.27 1.27)
				)
				(justify mirror)
			)
		)
		(duplicate_pad_numbers_are_jumpers no)
		(fp_line
			(start -0.7874 0.4064)
			(end 0.7874 0.4064)
			(stroke
				(width 0.1524)
				(type default)
			)
			(layer "B.SilkS")
		)
		(fp_line
			(start 0.7874 0.4064)
			(end 0.7874 -0.4064)
			(stroke
				(width 0.1524)
				(type default)
			)
			(layer "B.SilkS")
		)
		(fp_line
			(start -0.7874 -0.4064)
			(end -0.7874 0.4064)
			(stroke
				(width 0.1524)
				(type default)
			)
			(layer "B.SilkS")
		)
		(fp_line
			(start 0.7874 -0.4064)
			(end -0.7874 -0.4064)
			(stroke
				(width 0.1524)
				(type default)
			)
			(layer "B.SilkS")
		)
		(fp_line
			(start -0.67945 0.3048)
			(end -0.120396 0.3048)
			(stroke
				(width 0.1)
				(type default)
			)
			(layer "B.Fab")
		)
		(fp_line
			(start -0.120396 0.3048)
			(end -0.120396 0.2794)
			(stroke
				(width 0.1)
				(type default)
			)
			(layer "B.Fab")
		)
		(fp_line
			(start 0.12065 0.3048)
			(end 0.67945 0.3048)
			(stroke
				(width 0.1)
				(type default)
			)
			(layer "B.Fab")
		)
		(fp_line
			(start 0.67945 0.3048)
			(end 0.67945 -0.305054)
			(stroke
				(width 0.1)
				(type default)
			)
			(layer "B.Fab")
		)
		(fp_line
			(start -0.120396 0.2794)
			(end 0.12065 0.2794)
			(stroke
				(width 0.1)
				(type default)
			)
			(layer "B.Fab")
		)
		(fp_line
			(start 0.12065 0.2794)
			(end 0.12065 0.3048)
			(stroke
				(width 0.1)
				(type default)
			)
			(layer "B.Fab")
		)
		(fp_line
			(start -0.12065 -0.2794)
			(end -0.12065 -0.3048)
			(stroke
				(width 0.1)
				(type default)
			)
			(layer "B.Fab")
		)
		(fp_line
			(start 0.12065 -0.2794)
			(end -0.12065 -0.2794)
			(stroke
				(width 0.1)
				(type default)
			)
			(layer "B.Fab")
		)
		(fp_line
			(start -0.67945 -0.3048)
			(end -0.67945 0.3048)
			(stroke
				(width 0.1)
				(type default)
			)
			(layer "B.Fab")
		)
		(fp_line
			(start -0.12065 -0.3048)
			(end -0.67945 -0.3048)
			(stroke
				(width 0.1)
				(type default)
			)
			(layer "B.Fab")
		)
		(fp_line
			(start 0.12065 -0.305054)
			(end 0.12065 -0.2794)
			(stroke
				(width 0.1)
				(type default)
			)
			(layer "B.Fab")
		)
		(fp_line
			(start 0.67945 -0.305054)
			(end 0.12065 -0.305054)
			(stroke
				(width 0.1)
				(type default)
			)
			(layer "B.Fab")
		)
		(pad "1" smd circle
			(at 0.40005 0 90)
			(size 0 0)
			(layers "B.Cu" "B.Mask" "B.Paste")
			(net "PVCCIN_CPU0_VOS6")
		)
		(pad "2" smd circle
			(at -0.40005 0 90)
			(size 0 0)
			(layers "B.Cu" "B.Mask" "B.Paste")
			(net "PVCCIN_CPU0")
		)
	)
	(footprint ""
		(layer "B.Cu")
		(at 157.24886 -11.250168 90)
		(property "Reference" "R3114"
			(at 0 0 90)
			(layer "B.SilkS")
			(hide yes)
			(effects
				(font
					(size 1.27 1.27)
				)
				(justify mirror)
			)
		)
		(property "Value" ""
			(at 0 0 90)
			(layer "B.Fab")
			(effects
				(font
					(size 1.27 1.27)
				)
				(justify mirror)
			)
		)
		(duplicate_pad_numbers_are_jumpers no)
		(fp_line
			(start 0.7874 -0.4064)
			(end -0.7874 -0.4064)
			(stroke
				(width 0.1524)
				(type default)
			)
			(layer "B.SilkS")
		)
		(fp_line
			(start -0.7874 -0.4064)
			(end -0.7874 0.4064)
			(stroke
				(width 0.1524)
				(type default)
			)
			(layer "B.SilkS")
		)
		(fp_line
			(start 0.7874 0.4064)
			(end 0.7874 -0.4064)
			(stroke
				(width 0.1524)
				(type default)
			)
			(layer "B.SilkS")
		)
		(fp_line
			(start -0.7874 0.4064)
			(end 0.7874 0.4064)
			(stroke
				(width 0.1524)
				(type default)
			)
			(layer "B.SilkS")
		)
		(fp_line
			(start 0.67945 -0.305054)
			(end 0.12065 -0.305054)
			(stroke
				(width 0.1)
				(type default)
			)
			(layer "B.Fab")
		)
		(fp_line
			(start 0.12065 -0.305054)
			(end 0.12065 -0.2794)
			(stroke
				(width 0.1)
				(type default)
			)
			(layer "B.Fab")
		)
		(fp_line
			(start -0.12065 -0.3048)
			(end -0.67945 -0.3048)
			(stroke
				(width 0.1)
				(type default)
			)
			(layer "B.Fab")
		)
		(fp_line
			(start -0.67945 -0.3048)
			(end -0.67945 0.3048)
			(stroke
				(width 0.1)
				(type default)
			)
			(layer "B.Fab")
		)
		(fp_line
			(start 0.12065 -0.2794)
			(end -0.12065 -0.2794)
			(stroke
				(width 0.1)
				(type default)
			)
			(layer "B.Fab")
		)
		(fp_line
			(start -0.12065 -0.2794)
			(end -0.12065 -0.3048)
			(stroke
				(width 0.1)
				(type default)
			)
			(layer "B.Fab")
		)
		(fp_line
			(start 0.12065 0.2794)
			(end 0.12065 0.3048)
			(stroke
				(width 0.1)
				(type default)
			)
			(layer "B.Fab")
		)
		(fp_line
			(start -0.120396 0.2794)
			(end 0.12065 0.2794)
			(stroke
				(width 0.1)
				(type default)
			)
			(layer "B.Fab")
		)
		(fp_line
			(start 0.67945 0.3048)
			(end 0.67945 -0.305054)
			(stroke
				(width 0.1)
				(type default)
			)
			(layer "B.Fab")
		)
		(fp_line
			(start 0.12065 0.3048)
			(end 0.67945 0.3048)
			(stroke
				(width 0.1)
				(type default)
			)
			(layer "B.Fab")
		)
		(fp_line
			(start -0.120396 0.3048)
			(end -0.120396 0.2794)
			(stroke
				(width 0.1)
				(type default)
			)
			(layer "B.Fab")
		)
		(fp_line
			(start -0.67945 0.3048)
			(end -0.120396 0.3048)
			(stroke
				(width 0.1)
				(type default)
			)
			(layer "B.Fab")
		)
		(pad "1" smd circle
			(at 0.40005 0 270)
			(size 0 0)
			(layers "B.Cu" "B.Mask" "B.Paste")
			(net "SMB_FAN_3V3AUX_SDA")
		)
		(pad "2" smd circle
			(at -0.40005 0 270)
			(size 0 0)
			(layers "B.Cu" "B.Mask" "B.Paste")
			(net "SMB_FAN_3V3AUX_R_SDA")
		)
	)
	(footprint ""
		(layer "B.Cu")
		(at 116.40312 -248.49836 -90)
		(property "Reference" "C314"
			(at 0 0 90)
			(layer "B.SilkS")
			(hide yes)
			(effects
				(font
					(size 1.27 1.27)
				)
				(justify mirror)
			)
		)
		(property "Value" ""
			(at 0 0 90)
			(layer "B.Fab")
			(effects
				(font
					(size 1.27 1.27)
				)
				(justify mirror)
			)
		)
		(duplicate_pad_numbers_are_jumpers no)
		(fp_line
			(start -1.524 0.762)
			(end 1.524 0.762)
			(stroke
				(width 0.1524)
				(type default)
			)
			(layer "B.SilkS")
		)
		(fp_line
			(start 1.524 0.762)
			(end 1.524 -0.762)
			(stroke
				(width 0.1524)
				(type default)
			)
			(layer "B.SilkS")
		)
		(fp_line
			(start -1.524 -0.762)
			(end -1.524 0.762)
			(stroke
				(width 0.1524)
				(type default)
			)
			(layer "B.SilkS")
		)
		(fp_line
			(start 1.524 -0.762)
			(end -1.524 -0.762)
			(stroke
				(width 0.1524)
				(type default)
			)
			(layer "B.SilkS")
		)
		(fp_line
			(start -1.1049 0.724916)
			(end -1.1049 -0.724916)
			(stroke
				(width 0.1)
				(type default)
			)
			(layer "B.Fab")
		)
		(fp_line
			(start 1.1049 0.724916)
			(end -1.1049 0.724916)
			(stroke
				(width 0.1)
				(type default)
			)
			(layer "B.Fab")
		)
		(fp_line
			(start -1.1049 -0.724916)
			(end 1.1049 -0.724916)
			(stroke
				(width 0.1)
				(type default)
			)
			(layer "B.Fab")
		)
		(fp_line
			(start 1.1049 -0.724916)
			(end 1.1049 0.724916)
			(stroke
				(width 0.1)
				(type default)
			)
			(layer "B.Fab")
		)
		(pad "1" smd rect
			(at 0.889 0 270)
			(size 1.016 1.27)
			(layers "B.Cu" "B.Mask" "B.Paste")
			(net "PVCCIN_CPU1")
		)
		(pad "2" smd rect
			(at -0.889 0 270)
			(size 1.016 1.27)
			(layers "B.Cu" "B.Mask" "B.Paste")
			(net "GND")
		)
	)
)
